(kicad_pcb
	(version 20260206)
	(generator "pcbnew")
	(generator_version "10.0")
	(general
		(thickness 1.6)
		(legacy_teardrops no)
	)
	(paper "A4")
	(title_block
		(title "01162023_DA0F0TEBIF0_F0T_Expander_BD_F_brd_V02_OCP.brd")
		(comment 1 "Grand Teton / footprints 9240-9247 of 9728")
	)
	(layers
		(0 "F.Cu" signal "TOP")
		(4 "In1.Cu" signal "GND")
		(6 "In2.Cu" signal "VCC")
		(8 "In3.Cu" signal "VCC1")
		(10 "In4.Cu" signal "GND1")
		(12 "In5.Cu" signal "IN1")
		(14 "In6.Cu" signal "GND2")
		(16 "In7.Cu" signal "IN2")
		(18 "In8.Cu" signal "GND3")
		(20 "In9.Cu" signal "IN3")
		(22 "In10.Cu" signal "GND4")
		(24 "In11.Cu" signal "IN4")
		(26 "In12.Cu" signal "GND5")
		(28 "In13.Cu" signal "IN5")
		(30 "In14.Cu" signal "GND6")
		(32 "In15.Cu" signal "IN6")
		(34 "In16.Cu" signal "GND7")
		(2 "B.Cu" signal "BOTTOM")
		(9 "F.Adhes" user "F.Adhesive")
		(11 "B.Adhes" user "B.Adhesive")
		(13 "F.Paste" user "Package Geometry/Pastemask Top")
		(15 "B.Paste" user "Package Geometry/Pastemask Bottom")
		(5 "F.SilkS" user "Ref Des/Silkscreen Top")
		(7 "B.SilkS" user "Ref Des/Silkscreen Bottom")
		(1 "F.Mask" user "Board Geometry/Soldermask Top")
		(3 "B.Mask" user "Board Geometry/Soldermask Bottom")
		(17 "Dwgs.User" user "User.Drawings")
		(19 "Cmts.User" user "User.Comments")
		(21 "Eco1.User" user "User.Eco1")
		(23 "Eco2.User" user "User.Eco2")
		(25 "Edge.Cuts" user "Board Geometry/Outline")
		(27 "Margin" user)
		(31 "F.CrtYd" user "Package Geometry/Place Bound Top")
		(29 "B.CrtYd" user "Package Geometry/Place Bound Bottom")
		(35 "F.Fab" user "Ref Des/Assembly Top")
		(33 "B.Fab" user "Ref Des/Assembly Bottom")
	)
	(footprint ""
		(layer "B.Cu")
		(at 123.100592 -293.660068 90)
		(property "Reference" "PC118"
			(at 0 0 90)
			(layer "B.SilkS")
			(hide yes)
			(effects
				(font
					(size 1.27 1.27)
				)
				(justify mirror)
			)
		)
		(property "Value" ""
			(at 0 0 90)
			(layer "B.Fab")
			(effects
				(font
					(size 1.27 1.27)
				)
				(justify mirror)
			)
		)
		(duplicate_pad_numbers_are_jumpers no)
		(fp_line
			(start 4.84378 -2.150618)
			(end 4.53898 -2.150618)
			(stroke
				(width 0.1524)
				(type default)
			)
			(layer "B.SilkS")
		)
		(fp_line
			(start 4.84378 -2.150618)
			(end 4.842256 2.163064)
			(stroke
				(width 0.1524)
				(type default)
			)
			(layer "B.SilkS")
		)
		(fp_line
			(start 4.69138 -2.150618)
			(end 4.692396 2.161032)
			(stroke
				(width 0.1524)
				(type default)
			)
			(layer "B.SilkS")
		)
		(fp_line
			(start 4.53898 -2.150618)
			(end 4.539742 2.152142)
			(stroke
				(width 0.1524)
				(type default)
			)
			(layer "B.SilkS")
		)
		(fp_line
			(start 4.53898 -2.15011)
			(end -4.53898 -2.15011)
			(stroke
				(width 0.1524)
				(type default)
			)
			(layer "B.SilkS")
		)
		(fp_line
			(start -4.53898 -2.15011)
			(end -4.53898 2.15011)
			(stroke
				(width 0.1524)
				(type default)
			)
			(layer "B.SilkS")
		)
		(fp_line
			(start 4.53898 2.15011)
			(end 4.53898 -2.15011)
			(stroke
				(width 0.1524)
				(type default)
			)
			(layer "B.SilkS")
		)
		(fp_line
			(start -4.53898 2.15011)
			(end 4.53898 2.15011)
			(stroke
				(width 0.1524)
				(type default)
			)
			(layer "B.SilkS")
		)
		(fp_line
			(start 4.83108 2.150364)
			(end 4.447794 2.149348)
			(stroke
				(width 0.1524)
				(type default)
			)
			(layer "B.SilkS")
		)
		(fp_line
			(start 3.64998 -2.15011)
			(end -3.64998 -2.15011)
			(stroke
				(width 0.1)
				(type default)
			)
			(layer "B.Fab")
		)
		(fp_line
			(start -3.64998 -2.15011)
			(end -3.64998 2.15011)
			(stroke
				(width 0.1)
				(type default)
			)
			(layer "B.Fab")
		)
		(fp_line
			(start 3.64998 2.15011)
			(end 3.64998 -2.15011)
			(stroke
				(width 0.1)
				(type default)
			)
			(layer "B.Fab")
		)
		(fp_line
			(start -3.64998 2.15011)
			(end 3.64998 2.15011)
			(stroke
				(width 0.1)
				(type default)
			)
			(layer "B.Fab")
		)
		(fp_text user "+"
			(at 6.214872 -0.337058 90)
			(unlocked yes)
			(layer "B.SilkS")
			(effects
				(font
					(size 1.905 1.4224)
					(thickness 0.1524)
				)
				(justify left mirror)
			)
		)
		(fp_text user "-"
			(at -4.313174 -0.094488 90)
			(unlocked yes)
			(layer "B.SilkS")
			(effects
				(font
					(size 1.905 1.4224)
					(thickness 0.1524)
				)
				(justify left mirror)
			)
		)
		(fp_text user "+"
			(at 6.214872 -0.337058 90)
			(unlocked yes)
			(layer "B.Fab")
			(effects
				(font
					(size 1.905 1.4224)
					(thickness 0.1524)
				)
				(justify left mirror)
			)
		)
		(fp_text user "-"
			(at -4.313174 -0.094488 90)
			(unlocked yes)
			(layer "B.Fab")
			(effects
				(font
					(size 1.905 1.4224)
					(thickness 0.1524)
				)
				(justify left mirror)
			)
		)
		(pad "1" smd rect
			(at 3.199892 0 270)
			(size 2.413 2.8194)
			(layers "B.Cu" "B.Mask" "B.Paste")
			(net "P0V8_PEX1")
		)
		(pad "2" smd rect
			(at -3.199892 0 270)
			(size 2.413 2.8194)
			(layers "B.Cu" "B.Mask" "B.Paste")
			(net "GND")
		)
	)
	(footprint ""
		(layer "B.Cu")
		(at 61.872622 -152.674574 90)
		(property "Reference" "C857"
			(at 0 0 90)
			(layer "B.SilkS")
			(hide yes)
			(effects
				(font
					(size 1.27 1.27)
				)
				(justify mirror)
			)
		)
		(property "Value" ""
			(at 0 0 90)
			(layer "B.Fab")
			(effects
				(font
					(size 1.27 1.27)
				)
				(justify mirror)
			)
		)
		(duplicate_pad_numbers_are_jumpers no)
		(fp_line
			(start 0.7874 -0.4064)
			(end -0.7874 -0.4064)
			(stroke
				(width 0.1524)
				(type default)
			)
			(layer "B.SilkS")
		)
		(fp_line
			(start -0.7874 -0.4064)
			(end -0.7874 0.4064)
			(stroke
				(width 0.1524)
				(type default)
			)
			(layer "B.SilkS")
		)
		(fp_line
			(start 0.7874 0.4064)
			(end 0.7874 -0.4064)
			(stroke
				(width 0.1524)
				(type default)
			)
			(layer "B.SilkS")
		)
		(fp_line
			(start -0.7874 0.4064)
			(end 0.7874 0.4064)
			(stroke
				(width 0.1524)
				(type default)
			)
			(layer "B.SilkS")
		)
		(fp_line
			(start 0.67945 -0.305054)
			(end 0.12065 -0.305054)
			(stroke
				(width 0.1)
				(type default)
			)
			(layer "B.Fab")
		)
		(fp_line
			(start 0.12065 -0.305054)
			(end 0.12065 -0.2794)
			(stroke
				(width 0.1)
				(type default)
			)
			(layer "B.Fab")
		)
		(fp_line
			(start -0.12065 -0.3048)
			(end -0.67945 -0.3048)
			(stroke
				(width 0.1)
				(type default)
			)
			(layer "B.Fab")
		)
		(fp_line
			(start -0.67945 -0.3048)
			(end -0.67945 0.3048)
			(stroke
				(width 0.1)
				(type default)
			)
			(layer "B.Fab")
		)
		(fp_line
			(start 0.12065 -0.2794)
			(end -0.12065 -0.2794)
			(stroke
				(width 0.1)
				(type default)
			)
			(layer "B.Fab")
		)
		(fp_line
			(start -0.12065 -0.2794)
			(end -0.12065 -0.3048)
			(stroke
				(width 0.1)
				(type default)
			)
			(layer "B.Fab")
		)
		(fp_line
			(start 0.12065 0.2794)
			(end 0.12065 0.3048)
			(stroke
				(width 0.1)
				(type default)
			)
			(layer "B.Fab")
		)
		(fp_line
			(start -0.120396 0.2794)
			(end 0.12065 0.2794)
			(stroke
				(width 0.1)
				(type default)
			)
			(layer "B.Fab")
		)
		(fp_line
			(start 0.67945 0.3048)
			(end 0.67945 -0.305054)
			(stroke
				(width 0.1)
				(type default)
			)
			(layer "B.Fab")
		)
		(fp_line
			(start 0.12065 0.3048)
			(end 0.67945 0.3048)
			(stroke
				(width 0.1)
				(type default)
			)
			(layer "B.Fab")
		)
		(fp_line
			(start -0.120396 0.3048)
			(end -0.120396 0.2794)
			(stroke
				(width 0.1)
				(type default)
			)
			(layer "B.Fab")
		)
		(fp_line
			(start -0.67945 0.3048)
			(end -0.120396 0.3048)
			(stroke
				(width 0.1)
				(type default)
			)
			(layer "B.Fab")
		)
		(pad "1" smd circle
			(at 0.40005 0 270)
			(size 0 0)
			(layers "B.Cu" "B.Mask" "B.Paste")
			(net "P3V3_AUX")
		)
		(pad "2" smd circle
			(at -0.40005 0 270)
			(size 0 0)
			(layers "B.Cu" "B.Mask" "B.Paste")
			(net "GND")
		)
	)
	(footprint ""
		(layer "B.Cu")
		(at 22.143974 -168.768522)
		(property "Reference" "R503"
			(at 0 0 0)
			(layer "B.SilkS")
			(hide yes)
			(effects
				(font
					(size 1.27 1.27)
				)
				(justify mirror)
			)
		)
		(property "Value" ""
			(at 0 0 0)
			(layer "B.Fab")
			(effects
				(font
					(size 1.27 1.27)
				)
				(justify mirror)
			)
		)
		(duplicate_pad_numbers_are_jumpers no)
		(fp_line
			(start -0.7874 -0.4064)
			(end -0.7874 0.4064)
			(stroke
				(width 0.1524)
				(type default)
			)
			(layer "B.SilkS")
		)
		(fp_line
			(start -0.7874 0.4064)
			(end 0.7874 0.4064)
			(stroke
				(width 0.1524)
				(type default)
			)
			(layer "B.SilkS")
		)
		(fp_line
			(start 0.7874 -0.4064)
			(end -0.7874 -0.4064)
			(stroke
				(width 0.1524)
				(type default)
			)
			(layer "B.SilkS")
		)
		(fp_line
			(start 0.7874 0.4064)
			(end 0.7874 -0.4064)
			(stroke
				(width 0.1524)
				(type default)
			)
			(layer "B.SilkS")
		)
		(fp_line
			(start -0.67945 -0.3048)
			(end -0.67945 0.3048)
			(stroke
				(width 0.1)
				(type default)
			)
			(layer "B.Fab")
		)
		(fp_line
			(start -0.67945 0.3048)
			(end -0.120396 0.3048)
			(stroke
				(width 0.1)
				(type default)
			)
			(layer "B.Fab")
		)
		(fp_line
			(start -0.12065 -0.3048)
			(end -0.67945 -0.3048)
			(stroke
				(width 0.1)
				(type default)
			)
			(layer "B.Fab")
		)
		(fp_line
			(start -0.12065 -0.2794)
			(end -0.12065 -0.3048)
			(stroke
				(width 0.1)
				(type default)
			)
			(layer "B.Fab")
		)
		(fp_line
			(start -0.120396 0.2794)
			(end 0.12065 0.2794)
			(stroke
				(width 0.1)
				(type default)
			)
			(layer "B.Fab")
		)
		(fp_line
			(start -0.120396 0.3048)
			(end -0.120396 0.2794)
			(stroke
				(width 0.1)
				(type default)
			)
			(layer "B.Fab")
		)
		(fp_line
			(start 0.12065 -0.305054)
			(end 0.12065 -0.2794)
			(stroke
				(width 0.1)
				(type default)
			)
			(layer "B.Fab")
		)
		(fp_line
			(start 0.12065 -0.2794)
			(end -0.12065 -0.2794)
			(stroke
				(width 0.1)
				(type default)
			)
			(layer "B.Fab")
		)
		(fp_line
			(start 0.12065 0.2794)
			(end 0.12065 0.3048)
			(stroke
				(width 0.1)
				(type default)
			)
			(layer "B.Fab")
		)
		(fp_line
			(start 0.12065 0.3048)
			(end 0.67945 0.3048)
			(stroke
				(width 0.1)
				(type default)
			)
			(layer "B.Fab")
		)
		(fp_line
			(start 0.67945 -0.305054)
			(end 0.12065 -0.305054)
			(stroke
				(width 0.1)
				(type default)
			)
			(layer "B.Fab")
		)
		(fp_line
			(start 0.67945 0.3048)
			(end 0.67945 -0.305054)
			(stroke
				(width 0.1)
				(type default)
			)
			(layer "B.Fab")
		)
		(pad "1" smd circle
			(at 0.40005 0 180)
			(size 0 0)
			(layers "B.Cu" "B.Mask" "B.Paste")
			(net "PWRGD_P12V_AUX_R")
		)
		(pad "2" smd circle
			(at -0.40005 0 180)
			(size 0 0)
			(layers "B.Cu" "B.Mask" "B.Paste")
			(net "P5V_AUX_EN")
		)
	)
	(footprint ""
		(layer "B.Cu")
		(at 242.447318 -266.794996 180)
		(property "Reference" "L115"
			(at 0 0 0)
			(layer "B.SilkS")
			(hide yes)
			(effects
				(font
					(size 1.27 1.27)
				)
				(justify mirror)
			)
		)
		(property "Value" ""
			(at 0 0 0)
			(layer "B.Fab")
			(effects
				(font
					(size 1.27 1.27)
				)
				(justify mirror)
			)
		)
		(duplicate_pad_numbers_are_jumpers no)
		(fp_line
			(start 2.248154 4.9911)
			(end -2.248154 4.9911)
			(stroke
				(width 0.1524)
				(type default)
			)
			(layer "B.SilkS")
		)
		(fp_line
			(start 2.248154 1.973326)
			(end 2.248154 4.9911)
			(stroke
				(width 0.1524)
				(type default)
			)
			(layer "B.SilkS")
		)
		(fp_line
			(start 2.248154 -4.9911)
			(end 2.248154 -1.990598)
			(stroke
				(width 0.1524)
				(type default)
			)
			(layer "B.SilkS")
		)
		(fp_line
			(start -2.248154 4.9911)
			(end -2.248154 1.973326)
			(stroke
				(width 0.1524)
				(type default)
			)
			(layer "B.SilkS")
		)
		(fp_line
			(start -2.248154 -1.990598)
			(end -2.248154 -4.9911)
			(stroke
				(width 0.1524)
				(type default)
			)
			(layer "B.SilkS")
		)
		(fp_line
			(start -2.248154 -4.9911)
			(end 2.248154 -4.9911)
			(stroke
				(width 0.1524)
				(type default)
			)
			(layer "B.SilkS")
		)
		(fp_line
			(start 1.700022 0.899922)
			(end -1.700022 0.899922)
			(stroke
				(width 0.1)
				(type default)
			)
			(layer "B.Fab")
		)
		(fp_line
			(start 1.700022 -0.899922)
			(end 1.700022 0.899922)
			(stroke
				(width 0.1)
				(type default)
			)
			(layer "B.Fab")
		)
		(fp_line
			(start -1.700022 0.899922)
			(end -1.700022 -0.899922)
			(stroke
				(width 0.1)
				(type default)
			)
			(layer "B.Fab")
		)
		(fp_line
			(start -1.700022 -0.899922)
			(end 1.700022 -0.899922)
			(stroke
				(width 0.1)
				(type default)
			)
			(layer "B.Fab")
		)
		(pad "1" smd rect
			(at 1.575054 0)
			(size 1.1684 9.8044)
			(layers "B.Cu" "B.Mask" "B.Paste")
			(net "P1V25_PEX2")
		)
		(pad "2" smd rect
			(at -1.575054 0)
			(size 1.1684 9.8044)
			(layers "B.Cu" "B.Mask" "B.Paste")
			(net "P1V25_SERDES_VDDPLL_PEX2")
		)
	)
	(footprint ""
		(layer "B.Cu")
		(at 47.77486 -296.64152 -90)
		(property "Reference" "C3041"
			(at 0 0 90)
			(layer "B.SilkS")
			(hide yes)
			(effects
				(font
					(size 1.27 1.27)
				)
				(justify mirror)
			)
		)
		(property "Value" ""
			(at 0 0 90)
			(layer "B.Fab")
			(effects
				(font
					(size 1.27 1.27)
				)
				(justify mirror)
			)
		)
		(duplicate_pad_numbers_are_jumpers no)
		(fp_line
			(start -0.299974 0.150114)
			(end 0.299974 0.150114)
			(stroke
				(width 0.1)
				(type default)
			)
			(layer "B.Fab")
		)
		(fp_line
			(start 0.299974 0.150114)
			(end 0.299974 -0.150114)
			(stroke
				(width 0.1)
				(type default)
			)
			(layer "B.Fab")
		)
		(fp_line
			(start -0.299974 -0.150114)
			(end -0.299974 0.150114)
			(stroke
				(width 0.1)
				(type default)
			)
			(layer "B.Fab")
		)
		(fp_line
			(start 0.299974 -0.150114)
			(end -0.299974 -0.150114)
			(stroke
				(width 0.1)
				(type default)
			)
			(layer "B.Fab")
		)
		(pad "1" smd rect
			(at 0.2667 0 90)
			(size 0.3048 0.381)
			(layers "B.Cu" "B.Mask" "B.Paste")
			(net "PCEPLL3_VDDA18_PEX0")
		)
		(pad "2" smd rect
			(at -0.2667 0 90)
			(size 0.3048 0.381)
			(layers "B.Cu" "B.Mask" "B.Paste")
			(net "GND")
		)
	)
	(footprint ""
		(layer "B.Cu")
		(at 291.46119 -202.474068 180)
		(property "Reference" "R1043"
			(at 0 0 0)
			(layer "B.SilkS")
			(hide yes)
			(effects
				(font
					(size 1.27 1.27)
				)
				(justify mirror)
			)
		)
		(property "Value" ""
			(at 0 0 0)
			(layer "B.Fab")
			(effects
				(font
					(size 1.27 1.27)
				)
				(justify mirror)
			)
		)
		(duplicate_pad_numbers_are_jumpers no)
		(fp_line
			(start 0.7874 0.4064)
			(end 0.7874 -0.4064)
			(stroke
				(width 0.1524)
				(type default)
			)
			(layer "B.SilkS")
		)
		(fp_line
			(start 0.7874 -0.4064)
			(end -0.7874 -0.4064)
			(stroke
				(width 0.1524)
				(type default)
			)
			(layer "B.SilkS")
		)
		(fp_line
			(start -0.7874 0.4064)
			(end 0.7874 0.4064)
			(stroke
				(width 0.1524)
				(type default)
			)
			(layer "B.SilkS")
		)
		(fp_line
			(start -0.7874 -0.4064)
			(end -0.7874 0.4064)
			(stroke
				(width 0.1524)
				(type default)
			)
			(layer "B.SilkS")
		)
		(fp_line
			(start 0.67945 0.3048)
			(end 0.67945 -0.305054)
			(stroke
				(width 0.1)
				(type default)
			)
			(layer "B.Fab")
		)
		(fp_line
			(start 0.67945 -0.305054)
			(end 0.12065 -0.305054)
			(stroke
				(width 0.1)
				(type default)
			)
			(layer "B.Fab")
		)
		(fp_line
			(start 0.12065 0.3048)
			(end 0.67945 0.3048)
			(stroke
				(width 0.1)
				(type default)
			)
			(layer "B.Fab")
		)
		(fp_line
			(start 0.12065 0.2794)
			(end 0.12065 0.3048)
			(stroke
				(width 0.1)
				(type default)
			)
			(layer "B.Fab")
		)
		(fp_line
			(start 0.12065 -0.2794)
			(end -0.12065 -0.2794)
			(stroke
				(width 0.1)
				(type default)
			)
			(layer "B.Fab")
		)
		(fp_line
			(start 0.12065 -0.305054)
			(end 0.12065 -0.2794)
			(stroke
				(width 0.1)
				(type default)
			)
			(layer "B.Fab")
		)
		(fp_line
			(start -0.120396 0.3048)
			(end -0.120396 0.2794)
			(stroke
				(width 0.1)
				(type default)
			)
			(layer "B.Fab")
		)
		(fp_line
			(start -0.120396 0.2794)
			(end 0.12065 0.2794)
			(stroke
				(width 0.1)
				(type default)
			)
			(layer "B.Fab")
		)
		(fp_line
			(start -0.12065 -0.2794)
			(end -0.12065 -0.3048)
			(stroke
				(width 0.1)
				(type default)
			)
			(layer "B.Fab")
		)
		(fp_line
			(start -0.12065 -0.3048)
			(end -0.67945 -0.3048)
			(stroke
				(width 0.1)
				(type default)
			)
			(layer "B.Fab")
		)
		(fp_line
			(start -0.67945 0.3048)
			(end -0.120396 0.3048)
			(stroke
				(width 0.1)
				(type default)
			)
			(layer "B.Fab")
		)
		(fp_line
			(start -0.67945 -0.3048)
			(end -0.67945 0.3048)
			(stroke
				(width 0.1)
				(type default)
			)
			(layer "B.Fab")
		)
		(pad "1" smd circle
			(at 0.40005 0)
			(size 0 0)
			(layers "B.Cu" "B.Mask" "B.Paste")
			(net "GND")
		)
		(pad "2" smd circle
			(at -0.40005 0)
			(size 0 0)
			(layers "B.Cu" "B.Mask" "B.Paste")
			(net "SPI_BIC1_MOSI_LS23_DIR3")
		)
	)
	(footprint ""
		(layer "B.Cu")
		(at 52.049934 -288.299906 90)
		(property "Reference" "C2931"
			(at 0 0 90)
			(layer "B.SilkS")
			(hide yes)
			(effects
				(font
					(size 1.27 1.27)
				)
				(justify mirror)
			)
		)
		(property "Value" ""
			(at 0 0 90)
			(layer "B.Fab")
			(effects
				(font
					(size 1.27 1.27)
				)
				(justify mirror)
			)
		)
		(duplicate_pad_numbers_are_jumpers no)
		(fp_line
			(start 0.299974 -0.150114)
			(end -0.299974 -0.150114)
			(stroke
				(width 0.1)
				(type default)
			)
			(layer "B.Fab")
		)
		(fp_line
			(start -0.299974 -0.150114)
			(end -0.299974 0.150114)
			(stroke
				(width 0.1)
				(type default)
			)
			(layer "B.Fab")
		)
		(fp_line
			(start 0.299974 0.150114)
			(end 0.299974 -0.150114)
			(stroke
				(width 0.1)
				(type default)
			)
			(layer "B.Fab")
		)
		(fp_line
			(start -0.299974 0.150114)
			(end 0.299974 0.150114)
			(stroke
				(width 0.1)
				(type default)
			)
			(layer "B.Fab")
		)
		(pad "1" smd rect
			(at 0.2667 0 270)
			(size 0.3048 0.381)
			(layers "B.Cu" "B.Mask" "B.Paste")
			(net "P1V25_PEX0")
		)
		(pad "2" smd rect
			(at -0.2667 0 270)
			(size 0.3048 0.381)
			(layers "B.Cu" "B.Mask" "B.Paste")
			(net "GND")
		)
	)
	(footprint ""
		(layer "B.Cu")
		(at 179.55006 -292.099746 90)
		(property "Reference" "C1495"
			(at 0 0 90)
			(layer "B.SilkS")
			(hide yes)
			(effects
				(font
					(size 1.27 1.27)
				)
				(justify mirror)
			)
		)
		(property "Value" ""
			(at 0 0 90)
			(layer "B.Fab")
			(effects
				(font
					(size 1.27 1.27)
				)
				(justify mirror)
			)
		)
		(duplicate_pad_numbers_are_jumpers no)
		(fp_line
			(start 0.299974 -0.150114)
			(end -0.299974 -0.150114)
			(stroke
				(width 0.1)
				(type default)
			)
			(layer "B.Fab")
		)
		(fp_line
			(start -0.299974 -0.150114)
			(end -0.299974 0.150114)
			(stroke
				(width 0.1)
				(type default)
			)
			(layer "B.Fab")
		)
		(fp_line
			(start 0.299974 0.150114)
			(end 0.299974 -0.150114)
			(stroke
				(width 0.1)
				(type default)
			)
			(layer "B.Fab")
		)
		(fp_line
			(start -0.299974 0.150114)
			(end 0.299974 0.150114)
			(stroke
				(width 0.1)
				(type default)
			)
			(layer "B.Fab")
		)
		(pad "1" smd rect
			(at 0.2667 0 270)
			(size 0.3048 0.381)
			(layers "B.Cu" "B.Mask" "B.Paste")
			(net "P0V8_SERDES_VDDA_PEX1")
		)
		(pad "2" smd rect
			(at -0.2667 0 270)
			(size 0.3048 0.381)
			(layers "B.Cu" "B.Mask" "B.Paste")
			(net "GND")
		)
	)
)
